(kicad_pcb
	(version 20241229)
	(generator "pcbnew")
	(generator_version "9.0")
	(general
		(thickness 1.61)
		(legacy_teardrops no)
	)
	(paper "A3")
	(title_block
		(title "SO-DIMM DDR5 Tester")
		(date "2025-11-26")
		(rev "1.3.0")
		(comment 9 "footprints 541-547 of 627")
	)
	(layers
		(0 "F.Cu" signal)
		(4 "In1.Cu" power)
		(6 "In2.Cu" mixed)
		(8 "In3.Cu" power)
		(10 "In4.Cu" mixed)
		(12 "In5.Cu" power)
		(14 "In6.Cu" mixed)
		(16 "In7.Cu" power)
		(18 "In8.Cu" power)
		(20 "In9.Cu" mixed)
		(22 "In10.Cu" power)
		(2 "B.Cu" signal)
		(9 "F.Adhes" user "F.Adhesive")
		(11 "B.Adhes" user "B.Adhesive")
		(13 "F.Paste" user)
		(15 "B.Paste" user)
		(5 "F.SilkS" user "F.Silkscreen")
		(7 "B.SilkS" user "B.Silkscreen")
		(1 "F.Mask" user)
		(3 "B.Mask" user)
		(17 "Dwgs.User" user "User.Drawings")
		(19 "Cmts.User" user "User.Comments")
		(21 "Eco1.User" user "User.Eco1")
		(23 "Eco2.User" user "User.Eco2")
		(25 "Edge.Cuts" user)
		(27 "Margin" user)
		(31 "F.CrtYd" user "F.Courtyard")
		(29 "B.CrtYd" user "B.Courtyard")
		(35 "F.Fab" user)
		(33 "B.Fab" user)
	)
	(footprint "antmicro-footprints:C_0402_1005Metric"
		(layer "B.Cu")
		(at 141.85 160.7)
		(descr "Capacitor SMD 0402")
		(tags "capacitor SMD 0402")
		(property "Reference" "C168"
			(at 0 0.699 180)
			(layer "B.SilkS")
			(hide yes)
			(effects
				(font
					(size 0.7 0.7)
					(thickness 0.15)
				)
				(justify left bottom mirror)
			)
		)
		(property "Value" "C_100n_0402"
			(at -1.022927 -2.155213 180)
			(layer "B.Fab")
			(effects
				(font
					(size 0.7 0.7)
					(thickness 0.15)
				)
				(justify left bottom mirror)
			)
		)
		(property "Datasheet" "https://www.murata.com/products/productdetail?partno=GRM155R61H104KE14%23"
			(at 0 0 0)
			(layer "F.Fab")
			(hide yes)
			(effects
				(font
					(size 1.27 1.27)
					(thickness 0.15)
				)
			)
		)
		(property "Author" "Antmicro"
			(at 0 0 0)
			(layer "B.Fab")
			(hide yes)
			(effects
				(font
					(size 1 1)
					(thickness 0.15)
				)
				(justify mirror)
			)
		)
		(property "Dielectric" "X5R"
			(at 0 0 0)
			(layer "B.Fab")
			(hide yes)
			(effects
				(font
					(size 1 1)
					(thickness 0.15)
				)
				(justify mirror)
			)
		)
		(property "License" "Apache-2.0"
			(at 0 0 0)
			(layer "B.Fab")
			(hide yes)
			(effects
				(font
					(size 1 1)
					(thickness 0.15)
				)
				(justify mirror)
			)
		)
		(property "MPN" "GRM155R61H104KE14D"
			(at 0 0 0)
			(layer "B.Fab")
			(hide yes)
			(effects
				(font
					(size 1 1)
					(thickness 0.15)
				)
				(justify mirror)
			)
		)
		(property "Manufacturer" "Murata"
			(at 0 0 0)
			(layer "B.Fab")
			(hide yes)
			(effects
				(font
					(size 1 1)
					(thickness 0.15)
				)
				(justify mirror)
			)
		)
		(property "Val" "100n"
			(at 0 0 0)
			(layer "B.Fab")
			(hide yes)
			(effects
				(font
					(size 1 1)
					(thickness 0.15)
				)
				(justify mirror)
			)
		)
		(property "Voltage" "50V"
			(at 0 0 0)
			(layer "B.Fab")
			(hide yes)
			(effects
				(font
					(size 1 1)
					(thickness 0.15)
				)
				(justify mirror)
			)
		)
		(sheetname "/FPGA banks HP/")
		(sheetfile "fpga-banks-32-34.kicad_sch")
		(attr smd)
		(fp_rect
			(start -0.9659 0.481258)
			(end 0.9649 -0.458742)
			(stroke
				(width 0.05)
				(type solid)
			)
			(fill no)
			(layer "B.CrtYd")
		)
		(fp_line
			(start -0.499 -0.248)
			(end -0.499 0.25)
			(stroke
				(width 0.15)
				(type solid)
			)
			(layer "B.Fab")
		)
		(fp_line
			(start -0.499 0.25)
			(end 0.499 0.25)
			(stroke
				(width 0.15)
				(type solid)
			)
			(layer "B.Fab")
		)
		(fp_line
			(start 0.499 -0.248)
			(end -0.499 -0.248)
			(stroke
				(width 0.15)
				(type solid)
			)
			(layer "B.Fab")
		)
		(fp_line
			(start 0.499 0.25)
			(end 0.499 -0.248)
			(stroke
				(width 0.15)
				(type solid)
			)
			(layer "B.Fab")
		)
		(pad "1" smd roundrect
			(at -0.484 0)
			(size 0.59 0.64)
			(layers "B.Cu" "B.Mask" "B.Paste")
			(roundrect_rratio 0.25)
			(net 10 "/FPGA banks HP/VREF")
			(pintype "passive")
		)
		(pad "2" smd roundrect
			(at 0.484 0)
			(size 0.59 0.64)
			(layers "B.Cu" "B.Mask" "B.Paste")
			(roundrect_rratio 0.25)
			(net 1 "GND")
			(pintype "passive")
		)
	)
	(footprint "antmicro-footprints:C_0603_1608Metric"
		(layer "B.Cu")
		(at 132.100501 174.776)
		(descr "Capacitor SMD 0603")
		(tags "capacitor 0603")
		(property "Reference" "C17"
			(at 0 0.9 0)
			(layer "B.SilkS")
			(hide yes)
			(effects
				(font
					(size 0.7 0.7)
					(thickness 0.15)
				)
				(justify right bottom mirror)
			)
		)
		(property "Value" "C_47u_0603"
			(at 0 -1.6 0)
			(layer "B.Fab")
			(effects
				(font
					(size 0.7 0.7)
					(thickness 0.15)
				)
				(justify right bottom mirror)
			)
		)
		(property "Datasheet" "https://www.murata.com/products/productdetail?partno=GRM188R60J476ME15%23"
			(at 0 0 0)
			(layer "F.Fab")
			(hide yes)
			(effects
				(font
					(size 1.27 1.27)
					(thickness 0.15)
				)
			)
		)
		(property "Author" "Antmicro"
			(at 0 0 0)
			(layer "B.Fab")
			(hide yes)
			(effects
				(font
					(size 1 1)
					(thickness 0.15)
				)
				(justify mirror)
			)
		)
		(property "Dielectric" ""
			(at 0 0 0)
			(layer "B.Fab")
			(hide yes)
			(effects
				(font
					(size 1 1)
					(thickness 0.15)
				)
				(justify mirror)
			)
		)
		(property "License" "Apache-2.0"
			(at 0 0 0)
			(layer "B.Fab")
			(hide yes)
			(effects
				(font
					(size 1 1)
					(thickness 0.15)
				)
				(justify mirror)
			)
		)
		(property "MPN" "GRM188R60J476ME15D"
			(at 0 0 0)
			(layer "B.Fab")
			(hide yes)
			(effects
				(font
					(size 1 1)
					(thickness 0.15)
				)
				(justify mirror)
			)
		)
		(property "Manufacturer" "Murata"
			(at 0 0 0)
			(layer "B.Fab")
			(hide yes)
			(effects
				(font
					(size 1 1)
					(thickness 0.15)
				)
				(justify mirror)
			)
		)
		(property "Val" "47u"
			(at 0 0 0)
			(layer "B.Fab")
			(hide yes)
			(effects
				(font
					(size 1 1)
					(thickness 0.15)
				)
				(justify mirror)
			)
		)
		(property "Voltage" ""
			(at 0 0 0)
			(layer "B.Fab")
			(hide yes)
			(effects
				(font
					(size 1 1)
					(thickness 0.15)
				)
				(justify mirror)
			)
		)
		(sheetname "/FPGA power/")
		(sheetfile "fpga-power.kicad_sch")
		(attr smd)
		(fp_line
			(start -0.3 -0.3)
			(end 0.3 -0.3)
			(stroke
				(width 0.15)
				(type solid)
			)
			(layer "B.SilkS")
		)
		(fp_line
			(start -0.3 0.3)
			(end 0.3 0.3)
			(stroke
				(width 0.15)
				(type solid)
			)
			(layer "B.SilkS")
		)
		(fp_rect
			(start -1.24 0.7)
			(end 1.24 -0.7)
			(stroke
				(width 0.05)
				(type solid)
			)
			(fill no)
			(layer "B.CrtYd")
		)
		(fp_rect
			(start -0.8 0.4)
			(end 0.8 -0.4)
			(stroke
				(width 0.15)
				(type solid)
			)
			(fill no)
			(layer "B.Fab")
		)
		(pad "1" smd roundrect
			(at -0.7 0)
			(size 0.6 0.8)
			(layers "B.Cu" "B.Mask" "B.Paste")
			(roundrect_rratio 0.2)
			(net 200 "+3V3")
			(pintype "passive")
		)
		(pad "2" smd roundrect
			(at 0.7 0)
			(size 0.6 0.8)
			(layers "B.Cu" "B.Mask" "B.Paste")
			(roundrect_rratio 0.2)
			(net 1 "GND")
			(pintype "passive")
		)
	)
	(footprint "antmicro-footprints:TP_SMD_1mm"
		(layer "B.Cu")
		(at 189.1 177 180)
		(property "Reference" "TP59"
			(at 0.6 -0.5 0)
			(layer "B.SilkS")
			(effects
				(font
					(size 0.7 0.7)
					(thickness 0.15)
				)
				(justify left bottom mirror)
			)
		)
		(property "Value" "TP_1mm_SMD"
			(at 0 -1.4 0)
			(layer "B.Fab")
			(effects
				(font
					(size 0.7 0.7)
					(thickness 0.15)
				)
				(justify left bottom mirror)
			)
		)
		(property "MPN" ""
			(at 0 0 0)
			(unlocked yes)
			(layer "B.Fab")
			(hide yes)
			(effects
				(font
					(size 1 1)
					(thickness 0.15)
				)
				(justify mirror)
			)
		)
		(property "Manufacturer" ""
			(at 0 0 0)
			(unlocked yes)
			(layer "B.Fab")
			(hide yes)
			(effects
				(font
					(size 1 1)
					(thickness 0.15)
				)
				(justify mirror)
			)
		)
		(property "Author" "Antmicro"
			(at 0 0 0)
			(unlocked yes)
			(layer "B.Fab")
			(hide yes)
			(effects
				(font
					(size 1 1)
					(thickness 0.15)
				)
				(justify mirror)
			)
		)
		(property "License" "Apache-2.0"
			(at 0 0 0)
			(unlocked yes)
			(layer "B.Fab")
			(hide yes)
			(effects
				(font
					(size 1 1)
					(thickness 0.15)
				)
				(justify mirror)
			)
		)
		(sheetname "/Supply/")
		(sheetfile "supply.kicad_sch")
		(attr exclude_from_pos_files)
		(fp_circle
			(center 0 0)
			(end 0.6 0)
			(stroke
				(width 0.05)
				(type default)
			)
			(fill no)
			(layer "B.CrtYd")
		)
		(fp_text user "License: Apache-2.0"
			(at -0.5 -5.2 0)
			(layer "B.Fab")
			(effects
				(font
					(size 0.7 0.7)
					(thickness 0.15)
				)
				(justify left bottom mirror)
			)
		)
		(fp_text user "Author: Antmicro"
			(at -0.5 -4 0)
			(layer "B.Fab")
			(effects
				(font
					(size 0.7 0.7)
					(thickness 0.15)
				)
				(justify left bottom mirror)
			)
		)
		(fp_text user "${REFERENCE}"
			(at -0.5 -2.8 0)
			(layer "B.Fab")
			(effects
				(font
					(size 0.7 0.7)
					(thickness 0.15)
				)
				(justify left bottom mirror)
			)
		)
		(pad "1" smd circle
			(at 0 0 180)
			(size 1 1)
			(layers "B.Cu" "B.Mask")
			(net 51 "/Supply/1V8_local")
			(pinfunction "1")
			(pintype "passive")
		)
	)
	(footprint "antmicro-footprints:TP_SMD_1mm"
		(layer "B.Cu")
		(at 103.362904 187.9 90)
		(property "Reference" "TP54"
			(at -3.68 -0.272904 90)
			(layer "B.SilkS")
			(effects
				(font
					(size 0.7 0.7)
					(thickness 0.15)
				)
				(justify right top mirror)
			)
		)
		(property "Value" "TP_1mm_SMD"
			(at 0 -1.4 90)
			(layer "B.Fab")
			(effects
				(font
					(size 0.7 0.7)
					(thickness 0.15)
				)
				(justify right top mirror)
			)
		)
		(property "MPN" ""
			(at 0 0 270)
			(unlocked yes)
			(layer "B.Fab")
			(hide yes)
			(effects
				(font
					(size 1 1)
					(thickness 0.15)
				)
				(justify mirror)
			)
		)
		(property "Manufacturer" ""
			(at 0 0 270)
			(unlocked yes)
			(layer "B.Fab")
			(hide yes)
			(effects
				(font
					(size 1 1)
					(thickness 0.15)
				)
				(justify mirror)
			)
		)
		(property "Author" "Antmicro"
			(at 0 0 270)
			(unlocked yes)
			(layer "B.Fab")
			(hide yes)
			(effects
				(font
					(size 1 1)
					(thickness 0.15)
				)
				(justify mirror)
			)
		)
		(property "License" "Apache-2.0"
			(at 0 0 270)
			(unlocked yes)
			(layer "B.Fab")
			(hide yes)
			(effects
				(font
					(size 1 1)
					(thickness 0.15)
				)
				(justify mirror)
			)
		)
		(sheetname "/Debug FTDI/")
		(sheetfile "debug-ftdi.kicad_sch")
		(attr exclude_from_pos_files)
		(fp_circle
			(center 0 0)
			(end 0.6 0)
			(stroke
				(width 0.05)
				(type default)
			)
			(fill no)
			(layer "B.CrtYd")
		)
		(fp_text user "${REFERENCE}"
			(at -0.5 -2.8 90)
			(layer "B.Fab")
			(effects
				(font
					(size 0.7 0.7)
					(thickness 0.15)
				)
				(justify right top mirror)
			)
		)
		(fp_text user "Author: Antmicro"
			(at -0.5 -4 90)
			(layer "B.Fab")
			(effects
				(font
					(size 0.7 0.7)
					(thickness 0.15)
				)
				(justify right top mirror)
			)
		)
		(fp_text user "License: Apache-2.0"
			(at -0.5 -5.2 90)
			(layer "B.Fab")
			(effects
				(font
					(size 0.7 0.7)
					(thickness 0.15)
				)
				(justify right top mirror)
			)
		)
		(pad "1" smd circle
			(at 0 0 90)
			(size 1 1)
			(layers "B.Cu" "B.Mask")
			(net 672 "/Debug FTDI/FTDI.SDA")
			(pinfunction "1")
			(pintype "passive")
		)
	)
	(footprint "antmicro-footprints:C_0402_1005Metric"
		(layer "B.Cu")
		(at 134.375501 169.801 90)
		(descr "Capacitor SMD 0402 (1005 Metric), square (rectangular) end terminal, IPC_7351 nominal, (Body size source: IPC-SM-782 page 76, https://www.pcb-3d.com/wordpress/wp-content/uploads/ipc-sm-782a_amendment_1_and_2.pdf)")
		(tags "capacitor 0402")
		(property "Reference" "C44"
			(at 0 1.17 270)
			(layer "B.SilkS")
			(hide yes)
			(effects
				(font
					(size 0.7 0.7)
					(thickness 0.15)
				)
				(justify left bottom mirror)
			)
		)
		(property "Value" "C_100n_0402"
			(at 0 -1.169 270)
			(layer "B.Fab")
			(effects
				(font
					(size 0.7 0.7)
					(thickness 0.15)
				)
				(justify left bottom mirror)
			)
		)
		(property "Datasheet" "https://www.murata.com/products/productdetail?partno=GRM155R61H104KE14%23"
			(at 0 0 90)
			(layer "F.Fab")
			(hide yes)
			(effects
				(font
					(size 1.27 1.27)
					(thickness 0.15)
				)
			)
		)
		(property "Author" "Antmicro"
			(at 304.176501 35.425499 0)
			(layer "B.Fab")
			(hide yes)
			(effects
				(font
					(size 1 1)
					(thickness 0.15)
				)
				(justify mirror)
			)
		)
		(property "Dielectric" "X5R"
			(at 304.176501 35.425499 0)
			(layer "B.Fab")
			(hide yes)
			(effects
				(font
					(size 1 1)
					(thickness 0.15)
				)
				(justify mirror)
			)
		)
		(property "License" "Apache-2.0"
			(at 304.176501 35.425499 0)
			(layer "B.Fab")
			(hide yes)
			(effects
				(font
					(size 1 1)
					(thickness 0.15)
				)
				(justify mirror)
			)
		)
		(property "MPN" "GRM155R61H104KE14D"
			(at 304.176501 35.425499 0)
			(layer "B.Fab")
			(hide yes)
			(effects
				(font
					(size 1 1)
					(thickness 0.15)
				)
				(justify mirror)
			)
		)
		(property "Manufacturer" "Murata"
			(at 304.176501 35.425499 0)
			(layer "B.Fab")
			(hide yes)
			(effects
				(font
					(size 1 1)
					(thickness 0.15)
				)
				(justify mirror)
			)
		)
		(property "Val" "100n"
			(at 304.176501 35.425499 0)
			(layer "B.Fab")
			(hide yes)
			(effects
				(font
					(size 1 1)
					(thickness 0.15)
				)
				(justify mirror)
			)
		)
		(property "Voltage" "50V"
			(at 304.176501 35.425499 0)
			(layer "B.Fab")
			(hide yes)
			(effects
				(font
					(size 1 1)
					(thickness 0.15)
				)
				(justify mirror)
			)
		)
		(sheetname "/FPGA power/")
		(sheetfile "fpga-power.kicad_sch")
		(attr smd)
		(fp_rect
			(start -0.9656 0.4572)
			(end 0.9652 -0.4828)
			(stroke
				(width 0.05)
				(type solid)
			)
			(fill no)
			(layer "B.CrtYd")
		)
		(fp_line
			(start 0.498 -0.248)
			(end -0.5 -0.248)
			(stroke
				(width 0.15)
				(type solid)
			)
			(layer "B.Fab")
		)
		(fp_line
			(start -0.5 -0.248)
			(end -0.5 0.25)
			(stroke
				(width 0.15)
				(type solid)
			)
			(layer "B.Fab")
		)
		(fp_line
			(start 0.498 0.25)
			(end 0.498 -0.248)
			(stroke
				(width 0.15)
				(type solid)
			)
			(layer "B.Fab")
		)
		(fp_line
			(start -0.5 0.25)
			(end 0.498 0.25)
			(stroke
				(width 0.15)
				(type solid)
			)
			(layer "B.Fab")
		)
		(pad "1" smd roundrect
			(at -0.5 0)
			(size 0.6 0.6)
			(layers "B.Cu" "B.Mask" "B.Paste")
			(roundrect_rratio 0.25)
			(net 1 "GND")
			(pintype "passive")
		)
		(pad "2" smd roundrect
			(at 0.498 0 90)
			(size 0.6 0.6)
			(layers "B.Cu" "B.Mask" "B.Paste")
			(roundrect_rratio 0.25)
			(net 206 "+1V1")
			(pintype "passive")
		)
	)
	(footprint "antmicro-footprints:R_0402_1005Metric"
		(layer "B.Cu")
		(at 180.8 198.4 180)
		(descr "Resistor SMD 0402")
		(tags "resistor SMD 0402")
		(property "Reference" "R175"
			(at -3.95 -0.5 0)
			(layer "B.SilkS")
			(effects
				(font
					(size 0.7 0.7)
					(thickness 0.15)
				)
				(justify left bottom mirror)
			)
		)
		(property "Value" "R_0R_0402"
			(at -1.011843 -1.772047 0)
			(layer "B.Fab")
			(effects
				(font
					(size 0.7 0.7)
					(thickness 0.15)
				)
				(justify left bottom mirror)
			)
		)
		(property "Datasheet" "https://industrial.panasonic.com/cdbs/www-data/pdf/RDA0000/AOA0000C301.pdf"
			(at 0 0 180)
			(layer "F.Fab")
			(hide yes)
			(effects
				(font
					(size 1.27 1.27)
					(thickness 0.15)
				)
			)
		)
		(property "Author" "Antmicro"
			(at 361.6 396.8 0)
			(layer "B.Fab")
			(hide yes)
			(effects
				(font
					(size 1 1)
					(thickness 0.15)
				)
				(justify mirror)
			)
		)
		(property "Current" "1A"
			(at 361.6 396.8 0)
			(layer "B.Fab")
			(hide yes)
			(effects
				(font
					(size 1 1)
					(thickness 0.15)
				)
				(justify mirror)
			)
		)
		(property "License" "Apache-2.0"
			(at 361.6 396.8 0)
			(layer "B.Fab")
			(hide yes)
			(effects
				(font
					(size 1 1)
					(thickness 0.15)
				)
				(justify mirror)
			)
		)
		(property "MPN" "ERJ2GE0R00X"
			(at 361.6 396.8 0)
			(layer "B.Fab")
			(hide yes)
			(effects
				(font
					(size 1 1)
					(thickness 0.15)
				)
				(justify mirror)
			)
		)
		(property "Manufacturer" "Panasonic"
			(at 361.6 396.8 0)
			(layer "B.Fab")
			(hide yes)
			(effects
				(font
					(size 1 1)
					(thickness 0.15)
				)
				(justify mirror)
			)
		)
		(property "Tolerance" ""
			(at 361.6 396.8 0)
			(layer "B.Fab")
			(hide yes)
			(effects
				(font
					(size 1 1)
					(thickness 0.15)
				)
				(justify mirror)
			)
		)
		(property "Val" "0R"
			(at 361.6 396.8 0)
			(layer "B.Fab")
			(hide yes)
			(effects
				(font
					(size 1 1)
					(thickness 0.15)
				)
				(justify mirror)
			)
		)
		(sheetname "/I^{2}C/")
		(sheetfile "i2c.kicad_sch")
		(attr exclude_from_pos_files exclude_from_bom dnp)
		(fp_rect
			(start -0.93 0.47)
			(end 0.93 -0.47)
			(stroke
				(width 0.05)
				(type solid)
			)
			(fill no)
			(layer "B.CrtYd")
		)
		(fp_rect
			(start -0.5 0.25)
			(end 0.5 -0.25)
			(stroke
				(width 0.15)
				(type solid)
			)
			(fill no)
			(layer "B.Fab")
		)
		(pad "1" smd roundrect
			(at -0.485 0 180)
			(size 0.59 0.64)
			(layers "B.Cu" "B.Mask" "B.Paste")
			(roundrect_rratio 0.25)
			(net 690 "/I^{2}C/PWR.SDA")
			(pintype "passive")
		)
		(pad "2" smd roundrect
			(at 0.485 0 180)
			(size 0.59 0.64)
			(layers "B.Cu" "B.Mask" "B.Paste")
			(roundrect_rratio 0.25)
			(net 688 "/FPGA bank 14/FPGA_PWR.SDA")
			(pintype "passive")
		)
	)
	(footprint "antmicro-footprints:C_0603_1608Metric"
		(layer "B.Cu")
		(at 127.075501 174.801)
		(descr "Capacitor SMD 0603")
		(tags "capacitor 0603")
		(property "Reference" "C15"
			(at 0 0.9 0)
			(layer "B.SilkS")
			(hide yes)
			(effects
				(font
					(size 0.7 0.7)
					(thickness 0.15)
				)
				(justify right bottom mirror)
			)
		)
		(property "Value" "C_47u_0603"
			(at 0 -1.6 0)
			(layer "B.Fab")
			(effects
				(font
					(size 0.7 0.7)
					(thickness 0.15)
				)
				(justify right bottom mirror)
			)
		)
		(property "Datasheet" "https://www.murata.com/products/productdetail?partno=GRM188R60J476ME15%23"
			(at 0 0 0)
			(layer "F.Fab")
			(hide yes)
			(effects
				(font
					(size 1.27 1.27)
					(thickness 0.15)
				)
			)
		)
		(property "Author" "Antmicro"
			(at 0 0 0)
			(layer "B.Fab")
			(hide yes)
			(effects
				(font
					(size 1 1)
					(thickness 0.15)
				)
				(justify mirror)
			)
		)
		(property "Dielectric" ""
			(at 0 0 0)
			(layer "B.Fab")
			(hide yes)
			(effects
				(font
					(size 1 1)
					(thickness 0.15)
				)
				(justify mirror)
			)
		)
		(property "License" "Apache-2.0"
			(at 0 0 0)
			(layer "B.Fab")
			(hide yes)
			(effects
				(font
					(size 1 1)
					(thickness 0.15)
				)
				(justify mirror)
			)
		)
		(property "MPN" "GRM188R60J476ME15D"
			(at 0 0 0)
			(layer "B.Fab")
			(hide yes)
			(effects
				(font
					(size 1 1)
					(thickness 0.15)
				)
				(justify mirror)
			)
		)
		(property "Manufacturer" "Murata"
			(at 0 0 0)
			(layer "B.Fab")
			(hide yes)
			(effects
				(font
					(size 1 1)
					(thickness 0.15)
				)
				(justify mirror)
			)
		)
		(property "Val" "47u"
			(at 0 0 0)
			(layer "B.Fab")
			(hide yes)
			(effects
				(font
					(size 1 1)
					(thickness 0.15)
				)
				(justify mirror)
			)
		)
		(property "Voltage" ""
			(at 0 0 0)
			(layer "B.Fab")
			(hide yes)
			(effects
				(font
					(size 1 1)
					(thickness 0.15)
				)
				(justify mirror)
			)
		)
		(sheetname "/FPGA power/")
		(sheetfile "fpga-power.kicad_sch")
		(attr smd)
		(fp_line
			(start -0.3 -0.3)
			(end 0.3 -0.3)
			(stroke
				(width 0.15)
				(type solid)
			)
			(layer "B.SilkS")
		)
		(fp_line
			(start -0.3 0.3)
			(end 0.3 0.3)
			(stroke
				(width 0.15)
				(type solid)
			)
			(layer "B.SilkS")
		)
		(fp_rect
			(start -1.24 0.7)
			(end 1.24 -0.7)
			(stroke
				(width 0.05)
				(type solid)
			)
			(fill no)
			(layer "B.CrtYd")
		)
		(fp_rect
			(start -0.8 0.4)
			(end 0.8 -0.4)
			(stroke
				(width 0.15)
				(type solid)
			)
			(fill no)
			(layer "B.Fab")
		)
		(pad "1" smd roundrect
			(at -0.7 0)
			(size 0.6 0.8)
			(layers "B.Cu" "B.Mask" "B.Paste")
			(roundrect_rratio 0.2)
			(net 200 "+3V3")
			(pintype "passive")
		)
		(pad "2" smd roundrect
			(at 0.7 0)
			(size 0.6 0.8)
			(layers "B.Cu" "B.Mask" "B.Paste")
			(roundrect_rratio 0.2)
			(net 1 "GND")
			(pintype "passive")
		)
	)
)
